(kicad_pcb
	(version 20260206)
	(generator "pcbnew")
	(generator_version "10.0")
	(general
		(thickness 1.6)
		(legacy_teardrops no)
	)
	(paper "A4")
	(title_block
		(title "04192023_DAF0TMB3IC0_F0TG_MB_C_brd_V02_OCP.brd")
		(comment 1 "Grand Teton / footprints 1457-1461 of 8354")
	)
	(layers
		(0 "F.Cu" signal "TOP")
		(4 "In1.Cu" signal "GND")
		(6 "In2.Cu" signal "IN1")
		(8 "In3.Cu" signal "GND1")
		(10 "In4.Cu" signal "IN2")
		(12 "In5.Cu" signal "GND2")
		(14 "In6.Cu" signal "IN3")
		(16 "In7.Cu" signal "GND3")
		(18 "In8.Cu" signal "VCC")
		(20 "In9.Cu" signal "VCC1")
		(22 "In10.Cu" signal "GND4")
		(24 "In11.Cu" signal "IN4")
		(26 "In12.Cu" signal "GND5")
		(28 "In13.Cu" signal "IN5")
		(30 "In14.Cu" signal "GND6")
		(32 "In15.Cu" signal "IN6")
		(34 "In16.Cu" signal "GND7")
		(2 "B.Cu" signal "BOTTOM")
		(9 "F.Adhes" user "F.Adhesive")
		(11 "B.Adhes" user "B.Adhesive")
		(13 "F.Paste" user "Package Geometry/Pastemask Top")
		(15 "B.Paste" user "Package Geometry/Pastemask Bottom")
		(5 "F.SilkS" user "Ref Des/Silkscreen Top")
		(7 "B.SilkS" user "Ref Des/Silkscreen Bottom")
		(1 "F.Mask" user "Board Geometry/Soldermask Top")
		(3 "B.Mask" user "Board Geometry/Soldermask Bottom")
		(17 "Dwgs.User" user "User.Drawings")
		(19 "Cmts.User" user "User.Comments")
		(21 "Eco1.User" user "User.Eco1")
		(23 "Eco2.User" user "User.Eco2")
		(25 "Edge.Cuts" user "Board Geometry/Outline")
		(27 "Margin" user)
		(31 "F.CrtYd" user "Package Geometry/Place Bound Top")
		(29 "B.CrtYd" user "Package Geometry/Place Bound Bottom")
		(35 "F.Fab" user "Ref Des/Assembly Top")
		(33 "B.Fab" user "Ref Des/Assembly Bottom")
	)
	(footprint ""
		(layer "F.Cu")
		(at 21.512784 -392.396726 180)
		(property "Reference" "PR6631"
			(at 0 0 180)
			(layer "F.SilkS")
			(hide yes)
			(effects
				(font
					(size 1.27 1.27)
				)
			)
		)
		(property "Value" ""
			(at 0 0 180)
			(layer "F.Fab")
			(effects
				(font
					(size 1.27 1.27)
				)
			)
		)
		(duplicate_pad_numbers_are_jumpers no)
		(fp_line
			(start 0.7874 0.4064)
			(end -0.7874 0.4064)
			(stroke
				(width 0.1524)
				(type default)
			)
			(layer "F.SilkS")
		)
		(fp_line
			(start 0.7874 -0.4064)
			(end 0.7874 0.4064)
			(stroke
				(width 0.1524)
				(type default)
			)
			(layer "F.SilkS")
		)
		(fp_line
			(start -0.356616 -0.4064)
			(end 0.7874 -0.4064)
			(stroke
				(width 0.1524)
				(type default)
			)
			(layer "F.SilkS")
		)
		(fp_line
			(start -0.7874 0.4064)
			(end -0.7874 0.033274)
			(stroke
				(width 0.1524)
				(type default)
			)
			(layer "F.SilkS")
		)
		(fp_line
			(start 0.67945 0.3048)
			(end 0.120396 0.3048)
			(stroke
				(width 0.1)
				(type default)
			)
			(layer "F.Fab")
		)
		(fp_line
			(start 0.67945 -0.3048)
			(end 0.67945 0.3048)
			(stroke
				(width 0.1)
				(type default)
			)
			(layer "F.Fab")
		)
		(fp_line
			(start 0.12065 -0.2794)
			(end 0.12065 -0.3048)
			(stroke
				(width 0.1)
				(type default)
			)
			(layer "F.Fab")
		)
		(fp_line
			(start 0.12065 -0.3048)
			(end 0.67945 -0.3048)
			(stroke
				(width 0.1)
				(type default)
			)
			(layer "F.Fab")
		)
		(fp_line
			(start 0.120396 0.3048)
			(end 0.120396 0.2794)
			(stroke
				(width 0.1)
				(type default)
			)
			(layer "F.Fab")
		)
		(fp_line
			(start 0.120396 0.2794)
			(end -0.12065 0.2794)
			(stroke
				(width 0.1)
				(type default)
			)
			(layer "F.Fab")
		)
		(fp_line
			(start -0.12065 0.3048)
			(end -0.67945 0.3048)
			(stroke
				(width 0.1)
				(type default)
			)
			(layer "F.Fab")
		)
		(fp_line
			(start -0.12065 0.2794)
			(end -0.12065 0.3048)
			(stroke
				(width 0.1)
				(type default)
			)
			(layer "F.Fab")
		)
		(fp_line
			(start -0.12065 -0.2794)
			(end 0.12065 -0.2794)
			(stroke
				(width 0.1)
				(type default)
			)
			(layer "F.Fab")
		)
		(fp_line
			(start -0.12065 -0.305054)
			(end -0.12065 -0.2794)
			(stroke
				(width 0.1)
				(type default)
			)
			(layer "F.Fab")
		)
		(fp_line
			(start -0.67945 0.3048)
			(end -0.67945 -0.305054)
			(stroke
				(width 0.1)
				(type default)
			)
			(layer "F.Fab")
		)
		(fp_line
			(start -0.67945 -0.305054)
			(end -0.12065 -0.305054)
			(stroke
				(width 0.1)
				(type default)
			)
			(layer "F.Fab")
		)
		(pad "1" smd circle
			(at -0.40005 0 180)
			(size 0 0)
			(layers "F.Cu" "F.Mask" "F.Paste")
			(net "P0V9_RETIMER_CPU1_VOS2")
		)
		(pad "2" smd circle
			(at 0.40005 0 180)
			(size 0 0)
			(layers "F.Cu" "F.Mask" "F.Paste")
			(net "P0V9_CPU1_RT_2D")
		)
	)
	(footprint ""
		(layer "F.Cu")
		(at 123.127262 -52.534058)
		(property "Reference" "R617"
			(at 0 0 0)
			(layer "F.SilkS")
			(hide yes)
			(effects
				(font
					(size 1.27 1.27)
				)
			)
		)
		(property "Value" ""
			(at 0 0 0)
			(layer "F.Fab")
			(effects
				(font
					(size 1.27 1.27)
				)
			)
		)
		(duplicate_pad_numbers_are_jumpers no)
		(fp_line
			(start -0.7874 -0.4064)
			(end -0.623062 -0.4064)
			(stroke
				(width 0.1524)
				(type default)
			)
			(layer "F.SilkS")
		)
		(fp_line
			(start -0.7874 0.4064)
			(end -0.7874 -0.4064)
			(stroke
				(width 0.1524)
				(type default)
			)
			(layer "F.SilkS")
		)
		(fp_line
			(start 0.189738 -0.4064)
			(end 0.7874 -0.4064)
			(stroke
				(width 0.1524)
				(type default)
			)
			(layer "F.SilkS")
		)
		(fp_line
			(start 0.7874 -0.4064)
			(end 0.7874 0.4064)
			(stroke
				(width 0.1524)
				(type default)
			)
			(layer "F.SilkS")
		)
		(fp_line
			(start 0.7874 0.4064)
			(end -0.7874 0.4064)
			(stroke
				(width 0.1524)
				(type default)
			)
			(layer "F.SilkS")
		)
		(fp_line
			(start -0.67945 -0.305054)
			(end -0.12065 -0.305054)
			(stroke
				(width 0.1)
				(type default)
			)
			(layer "F.Fab")
		)
		(fp_line
			(start -0.67945 0.3048)
			(end -0.67945 -0.305054)
			(stroke
				(width 0.1)
				(type default)
			)
			(layer "F.Fab")
		)
		(fp_line
			(start -0.12065 -0.305054)
			(end -0.12065 -0.2794)
			(stroke
				(width 0.1)
				(type default)
			)
			(layer "F.Fab")
		)
		(fp_line
			(start -0.12065 -0.2794)
			(end 0.12065 -0.2794)
			(stroke
				(width 0.1)
				(type default)
			)
			(layer "F.Fab")
		)
		(fp_line
			(start -0.12065 0.2794)
			(end -0.12065 0.3048)
			(stroke
				(width 0.1)
				(type default)
			)
			(layer "F.Fab")
		)
		(fp_line
			(start -0.12065 0.3048)
			(end -0.67945 0.3048)
			(stroke
				(width 0.1)
				(type default)
			)
			(layer "F.Fab")
		)
		(fp_line
			(start 0.120396 0.2794)
			(end -0.12065 0.2794)
			(stroke
				(width 0.1)
				(type default)
			)
			(layer "F.Fab")
		)
		(fp_line
			(start 0.120396 0.3048)
			(end 0.120396 0.2794)
			(stroke
				(width 0.1)
				(type default)
			)
			(layer "F.Fab")
		)
		(fp_line
			(start 0.12065 -0.3048)
			(end 0.67945 -0.3048)
			(stroke
				(width 0.1)
				(type default)
			)
			(layer "F.Fab")
		)
		(fp_line
			(start 0.12065 -0.2794)
			(end 0.12065 -0.3048)
			(stroke
				(width 0.1)
				(type default)
			)
			(layer "F.Fab")
		)
		(fp_line
			(start 0.67945 -0.3048)
			(end 0.67945 0.3048)
			(stroke
				(width 0.1)
				(type default)
			)
			(layer "F.Fab")
		)
		(fp_line
			(start 0.67945 0.3048)
			(end 0.120396 0.3048)
			(stroke
				(width 0.1)
				(type default)
			)
			(layer "F.Fab")
		)
		(pad "1" smd circle
			(at -0.40005 0)
			(size 0 0)
			(layers "F.Cu" "F.Mask" "F.Paste")
			(net "PVDD18_S5_P0")
		)
		(pad "2" smd circle
			(at 0.40005 0)
			(size 0 0)
			(layers "F.Cu" "F.Mask" "F.Paste")
			(net "JTAG_BMC_R_D_OE")
		)
	)
	(footprint ""
		(layer "F.Cu")
		(at 109.13999 -23.534878 -90)
		(property "Reference" "R6331"
			(at 0 0 270)
			(layer "F.SilkS")
			(hide yes)
			(effects
				(font
					(size 1.27 1.27)
				)
			)
		)
		(property "Value" ""
			(at 0 0 270)
			(layer "F.Fab")
			(effects
				(font
					(size 1.27 1.27)
				)
			)
		)
		(duplicate_pad_numbers_are_jumpers no)
		(fp_line
			(start -0.7874 0.4064)
			(end -0.7874 -0.4064)
			(stroke
				(width 0.1524)
				(type default)
			)
			(layer "F.SilkS")
		)
		(fp_line
			(start 0.7874 0.4064)
			(end -0.7874 0.4064)
			(stroke
				(width 0.1524)
				(type default)
			)
			(layer "F.SilkS")
		)
		(fp_line
			(start -0.7874 -0.4064)
			(end 0.7874 -0.4064)
			(stroke
				(width 0.1524)
				(type default)
			)
			(layer "F.SilkS")
		)
		(fp_line
			(start 0.7874 -0.4064)
			(end 0.7874 0.4064)
			(stroke
				(width 0.1524)
				(type default)
			)
			(layer "F.SilkS")
		)
		(fp_line
			(start -0.67945 0.3048)
			(end -0.67945 -0.305054)
			(stroke
				(width 0.1)
				(type default)
			)
			(layer "F.Fab")
		)
		(fp_line
			(start -0.12065 0.3048)
			(end -0.67945 0.3048)
			(stroke
				(width 0.1)
				(type default)
			)
			(layer "F.Fab")
		)
		(fp_line
			(start 0.120396 0.3048)
			(end 0.120396 0.2794)
			(stroke
				(width 0.1)
				(type default)
			)
			(layer "F.Fab")
		)
		(fp_line
			(start 0.67945 0.3048)
			(end 0.120396 0.3048)
			(stroke
				(width 0.1)
				(type default)
			)
			(layer "F.Fab")
		)
		(fp_line
			(start -0.12065 0.2794)
			(end -0.12065 0.3048)
			(stroke
				(width 0.1)
				(type default)
			)
			(layer "F.Fab")
		)
		(fp_line
			(start 0.120396 0.2794)
			(end -0.12065 0.2794)
			(stroke
				(width 0.1)
				(type default)
			)
			(layer "F.Fab")
		)
		(fp_line
			(start -0.12065 -0.2794)
			(end 0.12065 -0.2794)
			(stroke
				(width 0.1)
				(type default)
			)
			(layer "F.Fab")
		)
		(fp_line
			(start 0.12065 -0.2794)
			(end 0.12065 -0.3048)
			(stroke
				(width 0.1)
				(type default)
			)
			(layer "F.Fab")
		)
		(fp_line
			(start 0.12065 -0.3048)
			(end 0.67945 -0.3048)
			(stroke
				(width 0.1)
				(type default)
			)
			(layer "F.Fab")
		)
		(fp_line
			(start 0.67945 -0.3048)
			(end 0.67945 0.3048)
			(stroke
				(width 0.1)
				(type default)
			)
			(layer "F.Fab")
		)
		(fp_line
			(start -0.67945 -0.305054)
			(end -0.12065 -0.305054)
			(stroke
				(width 0.1)
				(type default)
			)
			(layer "F.Fab")
		)
		(fp_line
			(start -0.12065 -0.305054)
			(end -0.12065 -0.2794)
			(stroke
				(width 0.1)
				(type default)
			)
			(layer "F.Fab")
		)
		(pad "1" smd circle
			(at -0.40005 0 270)
			(size 0 0)
			(layers "F.Cu" "F.Mask" "F.Paste")
			(net "USB_HUB2_TI_USB_R1_MRP_RBIAS")
		)
		(pad "2" smd circle
			(at 0.40005 0 270)
			(size 0 0)
			(layers "F.Cu" "F.Mask" "F.Paste")
			(net "GND")
		)
	)
	(footprint ""
		(layer "F.Cu")
		(at 120.142 -418.338 -90)
		(property "Reference" "Q103"
			(at 4.610862 -0.59436 90)
			(unlocked yes)
			(layer "F.SilkS")
			(effects
				(font
					(size 0.7874 0.5842)
					(thickness 0.1524)
				)
				(justify left)
			)
		)
		(property "Value" ""
			(at 0 0 270)
			(layer "F.Fab")
			(effects
				(font
					(size 1.27 1.27)
				)
			)
		)
		(duplicate_pad_numbers_are_jumpers no)
		(fp_line
			(start -1.332738 1.100074)
			(end -1.332738 -1.100074)
			(stroke
				(width 0.1524)
				(type default)
			)
			(layer "F.SilkS")
		)
		(fp_line
			(start 1.332738 1.100074)
			(end -1.332738 1.100074)
			(stroke
				(width 0.1524)
				(type default)
			)
			(layer "F.SilkS")
		)
		(fp_line
			(start 0 -0.541274)
			(end 0.4826 -1.100074)
			(stroke
				(width 0.1524)
				(type default)
			)
			(layer "F.SilkS")
		)
		(fp_line
			(start -1.332738 -1.100074)
			(end -0.4826 -1.100074)
			(stroke
				(width 0.1524)
				(type default)
			)
			(layer "F.SilkS")
		)
		(fp_line
			(start -0.4826 -1.100074)
			(end 0 -0.541274)
			(stroke
				(width 0.1524)
				(type default)
			)
			(layer "F.SilkS")
		)
		(fp_line
			(start 0.4826 -1.100074)
			(end 1.332738 -1.100074)
			(stroke
				(width 0.1524)
				(type default)
			)
			(layer "F.SilkS")
		)
		(fp_line
			(start 1.332738 -1.100074)
			(end 1.332738 1.100074)
			(stroke
				(width 0.1524)
				(type default)
			)
			(layer "F.SilkS")
		)
		(fp_poly
			(pts
				(xy -1.696974 -1.588262) (xy -2.438908 -1.844548) (xy -1.937258 -2.33553)
			)
			(stroke
				(width 0)
				(type default)
			)
			(fill yes)
			(layer "F.SilkS")
		)
		(fp_line
			(start -0.674878 1.100074)
			(end -0.674878 -1.100074)
			(stroke
				(width 0.1)
				(type default)
			)
			(layer "F.Fab")
		)
		(fp_line
			(start 0.674878 1.100074)
			(end -0.674878 1.100074)
			(stroke
				(width 0.1)
				(type default)
			)
			(layer "F.Fab")
		)
		(fp_line
			(start -0.674878 -1.100074)
			(end 0.674878 -1.100074)
			(stroke
				(width 0.1)
				(type default)
			)
			(layer "F.Fab")
		)
		(fp_line
			(start 0.674878 -1.100074)
			(end 0.674878 1.100074)
			(stroke
				(width 0.1)
				(type default)
			)
			(layer "F.Fab")
		)
		(fp_poly
			(pts
				(xy -2.2352 -0.298958) (xy -2.2352 -1.001014) (xy -1.533144 -0.649986)
			)
			(stroke
				(width 0)
				(type default)
			)
			(fill yes)
			(layer "F.Fab")
		)
		(pad "1" smd rect
			(at -0.94996 -0.649986)
			(size 0.4318 0.508)
			(layers "F.Cu" "F.Mask" "F.Paste")
			(net "GND")
		)
		(pad "2" smd rect
			(at -0.94996 0)
			(size 0.4318 0.508)
			(layers "F.Cu" "F.Mask" "F.Paste")
			(net "GPU_HMC_PRSNT_N")
		)
		(pad "3" smd rect
			(at -0.94996 0.649986)
			(size 0.4318 0.508)
			(layers "F.Cu" "F.Mask" "F.Paste")
			(net "GPU_HMC_PRSNT_ISO_N")
		)
		(pad "4" smd rect
			(at 0.94996 0.649986)
			(size 0.4318 0.508)
			(layers "F.Cu" "F.Mask" "F.Paste")
			(net "GND")
		)
		(pad "5" smd rect
			(at 0.94996 0)
			(size 0.4318 0.508)
			(layers "F.Cu" "F.Mask" "F.Paste")
			(net "GPU_HMC_PRSNT")
		)
		(pad "6" smd rect
			(at 0.94996 -0.649986)
			(size 0.4318 0.508)
			(layers "F.Cu" "F.Mask" "F.Paste")
			(net "GPU_HMC_PRSNT")
		)
	)
	(footprint ""
		(layer "F.Cu")
		(at 314.965588 5.082794)
		(property "Reference" "J71"
			(at -4.421886 0.954786 90)
			(unlocked yes)
			(layer "F.SilkS")
			(effects
				(font
					(size 0.7874 0.5842)
					(thickness 0.1524)
				)
				(justify left)
			)
		)
		(property "Value" ""
			(at 0 0 0)
			(layer "F.Fab")
			(effects
				(font
					(size 1.27 1.27)
				)
			)
		)
		(duplicate_pad_numbers_are_jumpers no)
		(fp_line
			(start -1.2192 -2.06756)
			(end 1.2192 -2.06756)
			(stroke
				(width 0.1524)
				(type default)
			)
			(layer "F.SilkS")
		)
		(fp_line
			(start -1.2192 2.06756)
			(end -1.2192 -2.06756)
			(stroke
				(width 0.1524)
				(type default)
			)
			(layer "F.SilkS")
		)
		(fp_line
			(start 1.2192 -2.06756)
			(end 1.2192 2.06756)
			(stroke
				(width 0.1524)
				(type default)
			)
			(layer "F.SilkS")
		)
		(fp_line
			(start 1.2192 2.06756)
			(end -1.2192 2.06756)
			(stroke
				(width 0.1524)
				(type default)
			)
			(layer "F.SilkS")
		)
		(pad "" np_thru_hole circle
			(at -2.8829 -1.27 270)
			(size 1.0414 1.0414)
			(drill 1.0414)
			(layers "*.Cu" "*.Mask")
			(clearance 0.381)
			(thermal_gap 0.381)
		)
		(pad "" np_thru_hole circle
			(at -2.8829 1.27 270)
			(size 1.0414 1.0414)
			(drill 1.0414)
			(layers "*.Cu" "*.Mask")
			(clearance 0.381)
			(thermal_gap 0.381)
		)
		(pad "" np_thru_hole circle
			(at 3.4671 -1.27 270)
			(size 1.0414 1.0414)
			(drill 1.0414)
			(layers "*.Cu" "*.Mask")
			(clearance 0.381)
			(thermal_gap 0.381)
		)
		(pad "" np_thru_hole circle
			(at 3.4671 1.27 270)
			(size 1.0414 1.0414)
			(drill 1.0414)
			(layers "*.Cu" "*.Mask")
			(clearance 0.381)
			(thermal_gap 0.381)
		)
		(pad "1" smd rect
			(at 0.8255 -0.249936 270)
			(size 0.3048 0.508)
			(layers "F.Cu" "F.Mask" "F.Paste")
			(net "DELTA_L_85_5INCH_IN1_DN")
		)
		(pad "2" smd rect
			(at 0.8255 0.249936 270)
			(size 0.3048 0.508)
			(layers "F.Cu" "F.Mask" "F.Paste")
			(net "DELTA_L_85_5INCH_IN1_DP")
		)
		(pad "3" smd circle
			(at 0 0)
			(size 0 0)
			(layers "F.Cu" "F.Mask" "F.Paste")
			(net "DELTA_L_GND_1")
		)
		(zone
			(layer "F.Cu")
			(hatch none 0.5)
			(connect_pads
				(clearance 0)
			)
			(min_thickness 0.25)
			(keepout
				(tracks not_allowed)
				(vias allowed)
				(pads allowed)
				(copperpour not_allowed)
				(footprints allowed)
			)
			(placement
				(enabled no)
				(sheetname "")
			)
			(fill
				(thermal_gap 0.5)
				(thermal_bridge_width 0.5)
				(island_removal_mode 0)
			)
			(polygon
				(pts
					(xy 316.083188 4.534154) (xy 316.083188 4.629658) (xy 315.486288 4.629658) (xy 315.486288 5.036058)
					(xy 316.083188 5.036058) (xy 316.083188 5.12953) (xy 315.486288 5.12953) (xy 315.486288 5.53593)
					(xy 316.083188 5.53593) (xy 316.083188 5.631434) (xy 315.384688 5.631434) (xy 315.384688 4.534154)
				)
			)
		)
		(zone
			(layers "F.Cu" "B.Cu" "In1.Cu" "In2.Cu" "In3.Cu" "In4.Cu" "In5.Cu" "In6.Cu"
				"In7.Cu" "In8.Cu" "In9.Cu" "In10.Cu" "In11.Cu" "In12.Cu" "In13.Cu" "In14.Cu"
				"In15.Cu" "In16.Cu"
			)
			(hatch none 0.5)
			(connect_pads
				(clearance 0)
			)
			(min_thickness 0.25)
			(keepout
				(tracks not_allowed)
				(vias allowed)
				(pads allowed)
				(copperpour not_allowed)
				(footprints allowed)
			)
			(placement
				(enabled no)
				(sheetname "")
			)
			(fill
				(thermal_gap 0.5)
				(thermal_bridge_width 0.5)
				(island_removal_mode 0)
			)
			(polygon
				(pts
					(arc
						(start 313.009788 3.812794)
						(mid 311.155588 3.812794)
						(end 313.009788 3.812794)
					)
				)
			)
		)
		(zone
			(layers "F.Cu" "B.Cu" "In1.Cu" "In2.Cu" "In3.Cu" "In4.Cu" "In5.Cu" "In6.Cu"
				"In7.Cu" "In8.Cu" "In9.Cu" "In10.Cu" "In11.Cu" "In12.Cu" "In13.Cu" "In14.Cu"
				"In15.Cu" "In16.Cu"
			)
			(hatch none 0.5)
			(connect_pads
				(clearance 0)
			)
			(min_thickness 0.25)
			(keepout
				(tracks not_allowed)
				(vias allowed)
				(pads allowed)
				(copperpour not_allowed)
				(footprints allowed)
			)
			(placement
				(enabled no)
				(sheetname "")
			)
			(fill
				(thermal_gap 0.5)
				(thermal_bridge_width 0.5)
				(island_removal_mode 0)
			)
			(polygon
				(pts
					(arc
						(start 313.009788 6.352794)
						(mid 311.155588 6.352794)
						(end 313.009788 6.352794)
					)
				)
			)
		)
		(zone
			(layers "F.Cu" "B.Cu" "In1.Cu" "In2.Cu" "In3.Cu" "In4.Cu" "In5.Cu" "In6.Cu"
				"In7.Cu" "In8.Cu" "In9.Cu" "In10.Cu" "In11.Cu" "In12.Cu" "In13.Cu" "In14.Cu"
				"In15.Cu" "In16.Cu"
			)
			(hatch none 0.5)
			(connect_pads
				(clearance 0)
			)
			(min_thickness 0.25)
			(keepout
				(tracks not_allowed)
				(vias allowed)
				(pads allowed)
				(copperpour not_allowed)
				(footprints allowed)
			)
			(placement
				(enabled no)
				(sheetname "")
			)
			(fill
				(thermal_gap 0.5)
				(thermal_bridge_width 0.5)
				(island_removal_mode 0)
			)
			(polygon
				(pts
					(arc
						(start 319.359788 3.812794)
						(mid 317.505588 3.812794)
						(end 319.359788 3.812794)
					)
				)
			)
		)
		(zone
			(layers "F.Cu" "B.Cu" "In1.Cu" "In2.Cu" "In3.Cu" "In4.Cu" "In5.Cu" "In6.Cu"
				"In7.Cu" "In8.Cu" "In9.Cu" "In10.Cu" "In11.Cu" "In12.Cu" "In13.Cu" "In14.Cu"
				"In15.Cu" "In16.Cu"
			)
			(hatch none 0.5)
			(connect_pads
				(clearance 0)
			)
			(min_thickness 0.25)
			(keepout
				(tracks not_allowed)
				(vias allowed)
				(pads allowed)
				(copperpour not_allowed)
				(footprints allowed)
			)
			(placement
				(enabled no)
				(sheetname "")
			)
			(fill
				(thermal_gap 0.5)
				(thermal_bridge_width 0.5)
				(island_removal_mode 0)
			)
			(polygon
				(pts
					(arc
						(start 319.359788 6.352794)
						(mid 317.505588 6.352794)
						(end 319.359788 6.352794)
					)
				)
			)
		)
	)
)
